(kicad_pcb
	(version 20260206)
	(generator "pcbnew")
	(generator_version "10.0")
	(general
		(thickness 1.6)
		(legacy_teardrops no)
	)
	(paper "A4")
	(title_block
		(title "Bryce Canyon_IOM_M2_16342-2_OCP.brd")
		(comment 1 "Bryce Canyon / footprints 785-791 of 1146")
	)
	(layers
		(0 "F.Cu" signal "TOP")
		(4 "In1.Cu" signal "L2GND")
		(6 "In2.Cu" signal "L3")
		(8 "In3.Cu" signal "L4VCC")
		(10 "In4.Cu" signal "L5VCC")
		(12 "In5.Cu" signal "L6")
		(14 "In6.Cu" signal "L7GND")
		(2 "B.Cu" signal "BOTTOM")
		(9 "F.Adhes" user "F.Adhesive")
		(11 "B.Adhes" user "B.Adhesive")
		(13 "F.Paste" user "Package Geometry/Pastemask Top")
		(15 "B.Paste" user "Package Geometry/Pastemask Bottom")
		(5 "F.SilkS" user "Ref Des/Silkscreen Top")
		(7 "B.SilkS" user "Ref Des/Silkscreen Bottom")
		(1 "F.Mask" user "Board Geometry/Soldermask Top")
		(3 "B.Mask" user "Board Geometry/Soldermask Bottom")
		(17 "Dwgs.User" user "User.Drawings")
		(19 "Cmts.User" user "User.Comments")
		(21 "Eco1.User" user "User.Eco1")
		(23 "Eco2.User" user "User.Eco2")
		(25 "Edge.Cuts" user "Board Geometry/Outline")
		(27 "Margin" user)
		(31 "F.CrtYd" user "Package Geometry/Place Bound Top")
		(29 "B.CrtYd" user "Package Geometry/Place Bound Bottom")
		(35 "F.Fab" user "Ref Des/Assembly Top")
		(33 "B.Fab" user "Ref Des/Assembly Bottom")
	)
	(footprint ""
		(layer "B.Cu")
		(at 210.753706 -86.56828 90)
		(property "Reference" "R801"
			(at 0 0 90)
			(layer "B.SilkS")
			(hide yes)
			(effects
				(font
					(size 1.27 1.27)
				)
				(justify mirror)
			)
		)
		(property "Value" "4K7R2F-GP"
			(at -0.064008 -3.993896 90)
			(unlocked yes)
			(layer "B.Fab")
			(hide yes)
			(effects
				(font
					(size 1.016 1.016)
					(thickness 0.1524)
				)
				(justify mirror)
			)
		)
		(property "Device Type" "R402H16"
			(at -0.064008 -5.517896 90)
			(unlocked yes)
			(layer "B.Fab")
			(hide yes)
			(effects
				(font
					(size 1.016 1.016)
					(thickness 0.1524)
				)
				(justify mirror)
			)
		)
		(duplicate_pad_numbers_are_jumpers no)
		(fp_line
			(start 0.508 -0.9398)
			(end 0.508 0.9398)
			(stroke
				(width 0.1524)
				(type default)
			)
			(layer "B.SilkS")
		)
		(fp_line
			(start -0.508 -0.9398)
			(end 0.508 -0.9398)
			(stroke
				(width 0.1524)
				(type default)
			)
			(layer "B.SilkS")
		)
		(fp_rect
			(start 0.508 0.9398)
			(end -0.508 -0.9398)
			(stroke
				(width 0)
				(type default)
			)
			(fill no)
			(layer "B.CrtYd")
		)
		(fp_rect
			(start 0.508 0.9398)
			(end -0.508 -0.9398)
			(stroke
				(width 0)
				(type default)
			)
			(fill no)
			(layer "B.Fab")
		)
		(pad "1" smd custom
			(at 0 -0.4445 270)
			(size 0.1397 0.1397)
			(layers "B.Cu" "B.Mask" "B.Paste")
			(net "Q20_G")
			(options
				(clearance outline)
				(anchor circle)
			)
			(primitives
				(gr_poly
					(pts
						(arc
							(start -0.1778 0.2794)
							(mid -0.249642 0.249642)
							(end -0.2794 0.1778)
						)
						(arc
							(start -0.2794 -0.1778)
							(mid -0.249642 -0.249642)
							(end -0.1778 -0.2794)
						)
						(arc
							(start 0.1778 -0.2794)
							(mid 0.249642 -0.249642)
							(end 0.2794 -0.1778)
						)
						(arc
							(start 0.2794 0.1778)
							(mid 0.249642 0.249642)
							(end 0.1778 0.2794)
						)
					)
					(width 0)
					(fill yes)
				)
			)
		)
		(pad "2" smd custom
			(at 0 0.4445 270)
			(size 0.1397 0.1397)
			(layers "B.Cu" "B.Mask" "B.Paste")
			(net "P3V3")
			(options
				(clearance outline)
				(anchor circle)
			)
			(primitives
				(gr_poly
					(pts
						(arc
							(start -0.1778 0.2794)
							(mid -0.249642 0.249642)
							(end -0.2794 0.1778)
						)
						(arc
							(start -0.2794 -0.1778)
							(mid -0.249642 -0.249642)
							(end -0.1778 -0.2794)
						)
						(arc
							(start 0.1778 -0.2794)
							(mid 0.249642 -0.249642)
							(end 0.2794 -0.1778)
						)
						(arc
							(start 0.2794 0.1778)
							(mid 0.249642 0.249642)
							(end 0.1778 0.2794)
						)
					)
					(width 0)
					(fill yes)
				)
			)
		)
	)
	(footprint ""
		(layer "B.Cu")
		(at 58.7756 -128.3462 -90)
		(property "Reference" "R708"
			(at 0 0 90)
			(layer "B.SilkS")
			(hide yes)
			(effects
				(font
					(size 1.27 1.27)
				)
				(justify mirror)
			)
		)
		(property "Value" "10KR2F-2-GP"
			(at -0.064008 -3.993896 270)
			(unlocked yes)
			(layer "B.Fab")
			(hide yes)
			(effects
				(font
					(size 1.016 1.016)
					(thickness 0.1524)
				)
				(justify mirror)
			)
		)
		(property "Device Type" "R402H16"
			(at -0.064008 -5.517896 270)
			(unlocked yes)
			(layer "B.Fab")
			(hide yes)
			(effects
				(font
					(size 1.016 1.016)
					(thickness 0.1524)
				)
				(justify mirror)
			)
		)
		(duplicate_pad_numbers_are_jumpers no)
		(fp_line
			(start -0.508 -0.9398)
			(end 0.508 -0.9398)
			(stroke
				(width 0.1524)
				(type default)
			)
			(layer "B.SilkS")
		)
		(fp_line
			(start 0.508 -0.9398)
			(end 0.508 0.9398)
			(stroke
				(width 0.1524)
				(type default)
			)
			(layer "B.SilkS")
		)
		(fp_rect
			(start 0.508 0.9398)
			(end -0.508 -0.9398)
			(stroke
				(width 0)
				(type default)
			)
			(fill no)
			(layer "B.CrtYd")
		)
		(fp_rect
			(start 0.508 0.9398)
			(end -0.508 -0.9398)
			(stroke
				(width 0)
				(type default)
			)
			(fill no)
			(layer "B.Fab")
		)
		(pad "1" smd custom
			(at 0 -0.4445 90)
			(size 0.1397 0.1397)
			(layers "B.Cu" "B.Mask" "B.Paste")
			(net "SCC_STBY_PWR_EN")
			(options
				(clearance outline)
				(anchor circle)
			)
			(primitives
				(gr_poly
					(pts
						(arc
							(start -0.1778 0.2794)
							(mid -0.249642 0.249642)
							(end -0.2794 0.1778)
						)
						(arc
							(start -0.2794 -0.1778)
							(mid -0.249642 -0.249642)
							(end -0.1778 -0.2794)
						)
						(arc
							(start 0.1778 -0.2794)
							(mid 0.249642 -0.249642)
							(end 0.2794 -0.1778)
						)
						(arc
							(start 0.2794 0.1778)
							(mid 0.249642 0.249642)
							(end 0.1778 0.2794)
						)
					)
					(width 0)
					(fill yes)
				)
			)
		)
		(pad "2" smd custom
			(at 0 0.4445 90)
			(size 0.1397 0.1397)
			(layers "B.Cu" "B.Mask" "B.Paste")
			(net "GND")
			(options
				(clearance outline)
				(anchor circle)
			)
			(primitives
				(gr_poly
					(pts
						(arc
							(start -0.1778 0.2794)
							(mid -0.249642 0.249642)
							(end -0.2794 0.1778)
						)
						(arc
							(start -0.2794 -0.1778)
							(mid -0.249642 -0.249642)
							(end -0.1778 -0.2794)
						)
						(arc
							(start 0.1778 -0.2794)
							(mid 0.249642 -0.249642)
							(end 0.2794 -0.1778)
						)
						(arc
							(start 0.2794 0.1778)
							(mid 0.249642 0.249642)
							(end 0.1778 0.2794)
						)
					)
					(width 0)
					(fill yes)
				)
			)
		)
	)
	(footprint ""
		(layer "B.Cu")
		(at 229.02926 -101.966776 180)
		(property "Reference" "C637"
			(at 0 0 0)
			(layer "B.SilkS")
			(hide yes)
			(effects
				(font
					(size 1.27 1.27)
				)
				(justify mirror)
			)
		)
		(property "Value" "SC10U16V5KX-7-GP-U"
			(at 0.0762 -6.1214 180)
			(unlocked yes)
			(layer "B.Fab")
			(hide yes)
			(effects
				(font
					(size 1.016 1.016)
					(thickness 0.1524)
				)
				(justify mirror)
			)
		)
		(property "Device Type" "C805H58"
			(at 0.0762 -8.1534 180)
			(unlocked yes)
			(layer "B.Fab")
			(hide yes)
			(effects
				(font
					(size 1.016 1.016)
					(thickness 0.1524)
				)
				(justify mirror)
			)
		)
		(duplicate_pad_numbers_are_jumpers no)
		(fp_line
			(start -0.635 0)
			(end 0.635 0)
			(stroke
				(width 0.508)
				(type default)
			)
			(layer "B.SilkS")
		)
		(fp_rect
			(start 0.9652 1.778)
			(end -0.9652 -1.778)
			(stroke
				(width 0)
				(type default)
			)
			(fill no)
			(layer "B.CrtYd")
		)
		(fp_poly
			(pts
				(xy 0.9652 -1.778) (xy -0.9652 -1.778) (xy -0.9652 1.778) (xy 0.9652 1.778)
			)
			(stroke
				(width 0)
				(type default)
			)
			(fill no)
			(layer "B.Fab")
		)
		(pad "1" smd rect
			(at 0 -0.9652)
			(size 1.397 1.143)
			(layers "B.Cu" "B.Mask" "B.Paste")
			(net "P12V_STBY_VIN_U81")
		)
		(pad "2" smd rect
			(at 0 0.9652)
			(size 1.397 1.143)
			(layers "B.Cu" "B.Mask" "B.Paste")
			(net "GND")
		)
	)
	(footprint ""
		(layer "B.Cu")
		(at 43.331638 -137.122408)
		(property "Reference" "TP29"
			(at 0 0 0)
			(layer "B.SilkS")
			(hide yes)
			(effects
				(font
					(size 1.27 1.27)
				)
				(justify mirror)
			)
		)
		(property "Value" "TPAD28-2-GP"
			(at 0.0127 -1.6637 0)
			(unlocked yes)
			(layer "B.Fab")
			(hide yes)
			(effects
				(font
					(size 1.016 1.016)
					(thickness 0.1524)
				)
				(justify mirror)
			)
		)
		(property "Device Type" "TPAD28"
			(at 0.0127 -3.1877 0)
			(unlocked yes)
			(layer "B.Fab")
			(hide yes)
			(effects
				(font
					(size 1.016 1.016)
					(thickness 0.1524)
				)
				(justify mirror)
			)
		)
		(duplicate_pad_numbers_are_jumpers no)
		(fp_poly
			(pts
				(arc
					(start 0.3556 0)
					(mid -0.3556 0)
					(end 0.3556 0)
				)
			)
			(stroke
				(width 0)
				(type default)
			)
			(fill no)
			(layer "B.CrtYd")
		)
		(fp_poly
			(pts
				(arc
					(start 0.6096 0)
					(mid -0.6096 0)
					(end 0.6096 0)
				)
			)
			(stroke
				(width 0)
				(type default)
			)
			(fill no)
			(layer "B.Fab")
		)
		(pad "1" smd circle
			(at 0 0 180)
			(size 0.7112 0.7112)
			(layers "B.Cu" "B.Mask" "B.Paste")
			(net "TP_BMC_GPIOR5")
		)
	)
	(footprint ""
		(layer "B.Cu")
		(at 209.427064 -88.954356 -90)
		(property "Reference" "Q21"
			(at 0 0 90)
			(layer "B.SilkS")
			(hide yes)
			(effects
				(font
					(size 1.27 1.27)
				)
				(justify mirror)
			)
		)
		(property "Value" "2N7002K-1-GP"
			(at -0.127 -8.9662 270)
			(unlocked yes)
			(layer "B.Fab")
			(hide yes)
			(effects
				(font
					(size 1.016 1.016)
					(thickness 0.1524)
				)
				(justify mirror)
			)
		)
		(property "Device Type" "SOT23DGS2D4H44"
			(at -0.127 -10.4902 270)
			(unlocked yes)
			(layer "B.Fab")
			(hide yes)
			(effects
				(font
					(size 1.016 1.016)
					(thickness 0.1524)
				)
				(justify mirror)
			)
		)
		(duplicate_pad_numbers_are_jumpers no)
		(fp_line
			(start -1.651 1.778)
			(end -1.651 -1.778)
			(stroke
				(width 0.1524)
				(type default)
			)
			(layer "B.SilkS")
		)
		(fp_line
			(start 1.651 1.778)
			(end -1.651 1.778)
			(stroke
				(width 0.1524)
				(type default)
			)
			(layer "B.SilkS")
		)
		(fp_line
			(start -1.651 -1.778)
			(end 1.651 -1.778)
			(stroke
				(width 0.1524)
				(type default)
			)
			(layer "B.SilkS")
		)
		(fp_line
			(start 1.651 -1.778)
			(end 1.651 1.778)
			(stroke
				(width 0.1524)
				(type default)
			)
			(layer "B.SilkS")
		)
		(fp_poly
			(pts
				(xy 1.778 1.8796) (xy 1.778 -1.8796) (xy -1.778 -1.8796) (xy -1.778 1.8796)
			)
			(stroke
				(width 0)
				(type default)
			)
			(fill no)
			(layer "B.CrtYd")
		)
		(fp_poly
			(pts
				(xy 1.778 1.8796) (xy 1.778 -1.8796) (xy -1.778 -1.8796) (xy -1.778 1.8796)
			)
			(stroke
				(width 0)
				(type default)
			)
			(fill no)
			(layer "B.Fab")
		)
		(pad "D" smd custom
			(at 0 -0.9525 90)
			(size 0.1905 0.1905)
			(layers "B.Cu" "B.Mask" "B.Paste")
			(net "P3V3_PG")
			(options
				(clearance outline)
				(anchor circle)
			)
			(primitives
				(gr_poly
					(pts
						(arc
							(start -0.1778 -0.5715)
							(mid -0.321484 -0.511984)
							(end -0.381 -0.3683)
						)
						(arc
							(start -0.381 0.3683)
							(mid -0.321484 0.511984)
							(end -0.1778 0.5715)
						)
						(arc
							(start 0.1778 0.5715)
							(mid 0.321484 0.511984)
							(end 0.381 0.3683)
						)
						(arc
							(start 0.381 -0.3683)
							(mid 0.321484 -0.511984)
							(end 0.1778 -0.5715)
						)
					)
					(width 0)
					(fill yes)
				)
			)
		)
		(pad "G" smd custom
			(at 0.98425 0.9525 90)
			(size 0.1905 0.1905)
			(layers "B.Cu" "B.Mask" "B.Paste")
			(net "Q21_G")
			(options
				(clearance outline)
				(anchor circle)
			)
			(primitives
				(gr_poly
					(pts
						(arc
							(start -0.1778 -0.5715)
							(mid -0.321484 -0.511984)
							(end -0.381 -0.3683)
						)
						(arc
							(start -0.381 0.3683)
							(mid -0.321484 0.511984)
							(end -0.1778 0.5715)
						)
						(arc
							(start 0.1778 0.5715)
							(mid 0.321484 0.511984)
							(end 0.381 0.3683)
						)
						(arc
							(start 0.381 -0.3683)
							(mid 0.321484 -0.511984)
							(end 0.1778 -0.5715)
						)
					)
					(width 0)
					(fill yes)
				)
			)
		)
		(pad "S" smd custom
			(at -0.98425 0.9525 90)
			(size 0.1905 0.1905)
			(layers "B.Cu" "B.Mask" "B.Paste")
			(net "GND")
			(options
				(clearance outline)
				(anchor circle)
			)
			(primitives
				(gr_poly
					(pts
						(arc
							(start -0.1778 -0.5715)
							(mid -0.321484 -0.511984)
							(end -0.381 -0.3683)
						)
						(arc
							(start -0.381 0.3683)
							(mid -0.321484 0.511984)
							(end -0.1778 0.5715)
						)
						(arc
							(start 0.1778 0.5715)
							(mid 0.321484 0.511984)
							(end 0.381 0.3683)
						)
						(arc
							(start 0.381 -0.3683)
							(mid 0.321484 -0.511984)
							(end 0.1778 -0.5715)
						)
					)
					(width 0)
					(fill yes)
				)
			)
		)
	)
	(footprint ""
		(layer "B.Cu")
		(at 125.349 -16.6624)
		(property "Reference" "R445"
			(at 0 0 0)
			(layer "B.SilkS")
			(hide yes)
			(effects
				(font
					(size 1.27 1.27)
				)
				(justify mirror)
			)
		)
		(property "Value" "49K9R2F-L-GP"
			(at -0.064008 -3.993896 0)
			(unlocked yes)
			(layer "B.Fab")
			(hide yes)
			(effects
				(font
					(size 1.016 1.016)
					(thickness 0.1524)
				)
				(justify mirror)
			)
		)
		(property "Device Type" "R402H16"
			(at -0.064008 -5.517896 0)
			(unlocked yes)
			(layer "B.Fab")
			(hide yes)
			(effects
				(font
					(size 1.016 1.016)
					(thickness 0.1524)
				)
				(justify mirror)
			)
		)
		(duplicate_pad_numbers_are_jumpers no)
		(fp_line
			(start -0.508 -0.9398)
			(end 0.508 -0.9398)
			(stroke
				(width 0.1524)
				(type default)
			)
			(layer "B.SilkS")
		)
		(fp_line
			(start 0.508 -0.9398)
			(end 0.508 0.9398)
			(stroke
				(width 0.1524)
				(type default)
			)
			(layer "B.SilkS")
		)
		(fp_rect
			(start 0.508 0.9398)
			(end -0.508 -0.9398)
			(stroke
				(width 0)
				(type default)
			)
			(fill no)
			(layer "B.CrtYd")
		)
		(fp_rect
			(start 0.508 0.9398)
			(end -0.508 -0.9398)
			(stroke
				(width 0)
				(type default)
			)
			(fill no)
			(layer "B.Fab")
		)
		(pad "1" smd custom
			(at 0 -0.4445 180)
			(size 0.1397 0.1397)
			(layers "B.Cu" "B.Mask" "B.Paste")
			(net "P12V_IOM")
			(options
				(clearance outline)
				(anchor circle)
			)
			(primitives
				(gr_poly
					(pts
						(arc
							(start -0.1778 0.2794)
							(mid -0.249642 0.249642)
							(end -0.2794 0.1778)
						)
						(arc
							(start -0.2794 -0.1778)
							(mid -0.249642 -0.249642)
							(end -0.1778 -0.2794)
						)
						(arc
							(start 0.1778 -0.2794)
							(mid 0.249642 -0.249642)
							(end 0.2794 -0.1778)
						)
						(arc
							(start 0.2794 0.1778)
							(mid 0.249642 0.249642)
							(end 0.1778 0.2794)
						)
					)
					(width 0)
					(fill yes)
				)
			)
		)
		(pad "2" smd custom
			(at 0 0.4445 180)
			(size 0.1397 0.1397)
			(layers "B.Cu" "B.Mask" "B.Paste")
			(net "MB0_CM_OV_R")
			(options
				(clearance outline)
				(anchor circle)
			)
			(primitives
				(gr_poly
					(pts
						(arc
							(start -0.1778 0.2794)
							(mid -0.249642 0.249642)
							(end -0.2794 0.1778)
						)
						(arc
							(start -0.2794 -0.1778)
							(mid -0.249642 -0.249642)
							(end -0.1778 -0.2794)
						)
						(arc
							(start 0.1778 -0.2794)
							(mid 0.249642 -0.249642)
							(end 0.2794 -0.1778)
						)
						(arc
							(start 0.2794 0.1778)
							(mid 0.249642 0.249642)
							(end 0.1778 0.2794)
						)
					)
					(width 0)
					(fill yes)
				)
			)
		)
	)
	(footprint ""
		(layer "B.Cu")
		(at 44.221908 -145.810732 -90)
		(property "Reference" "R141"
			(at 0 0 90)
			(layer "B.SilkS")
			(hide yes)
			(effects
				(font
					(size 1.27 1.27)
				)
				(justify mirror)
			)
		)
		(property "Value" "1KR2D-1-GP"
			(at -0.064008 -3.993896 270)
			(unlocked yes)
			(layer "B.Fab")
			(hide yes)
			(effects
				(font
					(size 1.016 1.016)
					(thickness 0.1524)
				)
				(justify mirror)
			)
		)
		(property "Device Type" "R402H16"
			(at -0.064008 -5.517896 270)
			(unlocked yes)
			(layer "B.Fab")
			(hide yes)
			(effects
				(font
					(size 1.016 1.016)
					(thickness 0.1524)
				)
				(justify mirror)
			)
		)
		(duplicate_pad_numbers_are_jumpers no)
		(fp_line
			(start -0.508 -0.9398)
			(end 0.508 -0.9398)
			(stroke
				(width 0.1524)
				(type default)
			)
			(layer "B.SilkS")
		)
		(fp_line
			(start 0.508 -0.9398)
			(end 0.508 0.9398)
			(stroke
				(width 0.1524)
				(type default)
			)
			(layer "B.SilkS")
		)
		(fp_rect
			(start 0.508 0.9398)
			(end -0.508 -0.9398)
			(stroke
				(width 0)
				(type default)
			)
			(fill no)
			(layer "B.CrtYd")
		)
		(fp_rect
			(start 0.508 0.9398)
			(end -0.508 -0.9398)
			(stroke
				(width 0)
				(type default)
			)
			(fill no)
			(layer "B.Fab")
		)
		(pad "1" smd custom
			(at 0 -0.4445 90)
			(size 0.1397 0.1397)
			(layers "B.Cu" "B.Mask" "B.Paste")
			(net "P1V2_STBY")
			(options
				(clearance outline)
				(anchor circle)
			)
			(primitives
				(gr_poly
					(pts
						(arc
							(start -0.1778 0.2794)
							(mid -0.249642 0.249642)
							(end -0.2794 0.1778)
						)
						(arc
							(start -0.2794 -0.1778)
							(mid -0.249642 -0.249642)
							(end -0.1778 -0.2794)
						)
						(arc
							(start 0.1778 -0.2794)
							(mid 0.249642 -0.249642)
							(end 0.2794 -0.1778)
						)
						(arc
							(start 0.2794 0.1778)
							(mid 0.249642 0.249642)
							(end 0.1778 0.2794)
						)
					)
					(width 0)
					(fill yes)
				)
			)
		)
		(pad "2" smd custom
			(at 0 0.4445 90)
			(size 0.1397 0.1397)
			(layers "B.Cu" "B.Mask" "B.Paste")
			(net "DDR_VREF")
			(options
				(clearance outline)
				(anchor circle)
			)
			(primitives
				(gr_poly
					(pts
						(arc
							(start -0.1778 0.2794)
							(mid -0.249642 0.249642)
							(end -0.2794 0.1778)
						)
						(arc
							(start -0.2794 -0.1778)
							(mid -0.249642 -0.249642)
							(end -0.1778 -0.2794)
						)
						(arc
							(start 0.1778 -0.2794)
							(mid 0.249642 -0.249642)
							(end 0.2794 -0.1778)
						)
						(arc
							(start 0.2794 0.1778)
							(mid 0.249642 0.249642)
							(end 0.1778 0.2794)
						)
					)
					(width 0)
					(fill yes)
				)
			)
		)
	)
)
